FILE_TYPE = MACRO_DRAWING;
SET COLOR_WIRE YELLOW;
SET COLOR_PROP ORANGE;
SET COLOR_DOT WHITE;
SET COLOR_ARC YELLOW;
SET COLOR_BODY GREEN;
SET COLOR_NOTE PURPLE;
SET PROP_DISPLAY VALUE;
SET PAGE_NUMBER P266;
FORCEADD QUANTA_TITLE_BLOCK_C..1
(-100 100);
FORCEPROP 1 LAST CUSTOM_TXT_CDS <NAME_2>
J 0
(-3275 150);
FORCEPROP 1 LAST CUSTOM_TXT_CDS <NAME_1>
J 0
(-3275 275);
FORCEPROP 1 LAST CUSTOM_TXT_CDS <Q_NUMBER>
J 0
(-1503 203);
DISPLAY 1.212766 (-1503 203);
FORCEPROP 1 LAST CUSTOM_TXT_CDS <Q_PROJ>
J 0
(-2482 202);
DISPLAY 1.212766 (-2482 202);
FORCEPROP 1 LAST CUSTOM_TXT_CDS <Q_REV>
J 0
(-284 203);
DISPLAY 1.212766 (-284 203);
FORCEPROP 1 LAST CUSTOM_TXT_CDS <CON_LAST_MODIFIED>
J 0
(-1985 115);
DISPLAY 0.978723 (-1985 115);
FORCEPROP 1 LAST CUSTOM_TXT_CDS <CON_PAGE_NUM> OF <CON_TOTAL_PAGES>
J 0
(-546 118);
DISPLAY 0.978723 (-546 118);
FORCEPROP 1 LAST Q_TITLE BLANK
J 0
(-9466 126);
DISPLAY 2.446809 (-9466 126);
PAINT GREEN (-9466 126);
FORCEPROP 1 LAST Q_DEPT 
J 1
(-3863 149);
DISPLAY 1.957447 (-3863 149);
PAINT GREEN (-3863 149);
FORCEPROP 2 LAST CDS_XR_PAGE_TITLE CR-280 : @S9S_MB_2U_LIB.S9S_MB_2U(SCH_1):PAGE280
J 0
(-7990 5350);
DISPLAY 0.638298 (-7990 5350);
PAINT PINK (-7990 5350);
DISPLAY INVISIBLE (-7990 5350);
FORCEPROP 2 LAST PAGE_BORDER TRUE
J 0
(-7990 5350);
DISPLAY 0.638298 (-7990 5350);
PAINT PINK (-7990 5350);
DISPLAY INVISIBLE (-7990 5350);
FORCEPROP 1 LAST CDS_LMAN_SYM_OUTLINE -9475,6775,100,-125
J 0
(-100 100);
DISPLAY 0.468085 (-100 100);
PAINT GREEN (-100 100);
DISPLAY INVISIBLE (-100 100);
FORCEPROP 2 LAST CDS_LIB pure_quanta
J 0
(-100 100);
DISPLAY INVISIBLE (-100 100);
FORCEPROP 1 LAST COMMENT_BODY TRUE
J 0
(-88 87);
DISPLAY 0.978723 (-88 87);
PAINT GREEN (-88 87);
DISPLAY INVISIBLE (-88 87);
FORCEPROP 2 LAST CUSTOM_TXT_CDS <XR_PAGE_TITLE>
J 0
(-7990 5350);
DISPLAY 0.638298 (-7990 5350);
PAINT PINK (-7990 5350);
DISPLAY INVISIBLE (-7990 5350);
FORCEPROP 0 LAST CDS_CON_LAST_MODIFIED Thu Aug 24 16:16:42 2023
J 0
(-1985 115);
DISPLAY INVISIBLE (-1985 115);
QUIT
